FILE_TYPE = MACRO_DRAWING;
SET COLOR_WIRE YELLOW;
SET COLOR_PROP ORANGE;
SET COLOR_DOT WHITE;
SET COLOR_ARC YELLOW;
SET COLOR_BODY GREEN;
SET COLOR_NOTE PURPLE;
SET PROP_DISPLAY VALUE;
SET PAGE_NUMBER P109;
FORCEADD QUANTA_TITLE_BLOCK_C..1
(-1325 3300);
FORCEPROP 1 LAST CUSTOM_TXT_CDS <NAME_2>
J 0
(-4500 3350);
FORCEPROP 1 LAST CUSTOM_TXT_CDS <NAME_1>
J 0
(-4500 3475);
FORCEPROP 1 LAST CUSTOM_TXT_CDS <Q_NUMBER>
J 0
(-2728 3403);
DISPLAY 1.212766 (-2728 3403);
FORCEPROP 1 LAST CUSTOM_TXT_CDS <Q_PROJ>
J 0
(-3707 3402);
DISPLAY 1.212766 (-3707 3402);
FORCEPROP 1 LAST CUSTOM_TXT_CDS <Q_REV>
J 0
(-1509 3403);
DISPLAY 1.212766 (-1509 3403);
FORCEPROP 1 LAST CUSTOM_TXT_CDS <CON_LAST_MODIFIED>
J 0
(-3210 3315);
DISPLAY 0.978723 (-3210 3315);
FORCEPROP 1 LAST CUSTOM_TXT_CDS <CON_PAGE_NUM> OF <CON_TOTAL_PAGES>
J 0
(-1771 3318);
DISPLAY 0.978723 (-1771 3318);
FORCEPROP 1 LAST Q_DEPT BU9
J 1
(-5088 3349);
DISPLAY 1.957447 (-5088 3349);
PAINT GREEN (-5088 3349);
FORCEPROP 1 LAST Q_TITLE Blank
J 0
(-10600 3400);
DISPLAY 2.446809 (-10600 3400);
PAINT GREEN (-10600 3400);
FORCEPROP 0 LAST CDS_CON_LAST_MODIFIED Wed Jul 21 11:36:02 2021
J 0
(-3210 3315);
DISPLAY INVISIBLE (-3210 3315);
FORCEPROP 2 LAST CDS_LIB pure_quanta
J 0
(-1325 3300);
DISPLAY INVISIBLE (-1325 3300);
FORCEPROP 1 LAST CDS_LMAN_SYM_OUTLINE -9475,6775,100,-125
J 0
(-1325 3300);
DISPLAY 0.468085 (-1325 3300);
PAINT GREEN (-1325 3300);
DISPLAY INVISIBLE (-1325 3300);
FORCEPROP 2 LAST PAGE_BORDER TRUE
J 0
(-9215 8550);
DISPLAY 0.638298 (-9215 8550);
PAINT PINK (-9215 8550);
DISPLAY INVISIBLE (-9215 8550);
FORCEPROP 1 LAST COMMENT_BODY TRUE
J 0
(-1313 3287);
DISPLAY 0.978723 (-1313 3287);
PAINT GREEN (-1313 3287);
DISPLAY INVISIBLE (-1313 3287);
FORCEPROP 2 LAST CUSTOM_TXT_CDS <XR_PAGE_TITLE>
J 0
(-9215 8550);
DISPLAY 0.638298 (-9215 8550);
PAINT PINK (-9215 8550);
DISPLAY INVISIBLE (-9215 8550);
FORCEPROP 2 LAST CDS_XR_PAGE_TITLE CR-109 : @T6G_MB_LIB.T6G(SCH_1):PAGE109
J 0
(-9215 8550);
DISPLAY 0.638298 (-9215 8550);
PAINT PINK (-9215 8550);
DISPLAY INVISIBLE (-9215 8550);
QUIT
